#ISCELL
  mstr_misc dns *
  *
#ISCELL
  pure_quanta quanta_title_block_c *
  *
#ISCELL
  standard offpage *
  page264_i1
#CELL
  pure_quanta q_res *
  page264_i10
#CELL
  pure_quanta q_res *
  page264_i11
#ISCELL
  standard offpage *
  page264_i12
#CELL
  pure_quanta q_res *
  page264_i13
#CELL
  pure_quanta q_res *
  page264_i14
#ISCELL
  standard offpage *
  page264_i15
#ISCELL
  standard offpage *
  page264_i16
#ISCELL
  logical_power universal_gnd *
  page264_i17
#CELL
  pure_quanta q_cap *
  page264_i18
#CELL
  pure_quanta q_cap *
  page264_i19
#ISCELL
  standard offpage *
  page264_i2
#ISCELL
  logical_power vcc15 *
  page264_i20
#ISCELL
  standard offpage *
  page264_i21
#ISCELL
  standard offpage *
  page264_i22
#ISCELL
  standard offpage *
  page264_i23
#CELL
  pure_quanta q_res *
  page264_i24
#CELL
  pure_quanta q_res *
  page264_i25
#ISCELL
  standard offpage *
  page264_i26
#ISCELL
  standard offpage *
  page264_i27
#ISCELL
  standard offpage *
  page264_i28
#ISCELL
  standard offpage *
  page264_i29
#ISCELL
  standard offpage *
  page264_i3
#CELL
  pure_quanta q_res *
  page264_i30
#CELL
  pure_quanta q_res *
  page264_i31
#CELL
  pure_quanta q_short *
  page264_i32
#ISCELL
  logical_power universal_gnd *
  page264_i33
#ISCELL
  logical_power vcc15 *
  page264_i34
#ISCELL
  logical_power vcc15 *
  page264_i35
#CELL
  pure_quanta q_res *
  page264_i36
#CELL
  pure_quanta q_cap *
  page264_i37
#CELL
  pure_quanta q_res *
  page264_i38
#CELL
  pure_quanta q_res *
  page264_i39
#ISCELL
  logical_power universal_gnd *
  page264_i4
#CELL
  pure_quanta q_res *
  page264_i40
#ISCELL
  logical_power vcc15 *
  page264_i41
#CELL
  pure_quanta q_res *
  page264_i42
#CELL
  pure_quanta q_res *
  page264_i43
#CELL
  pure_quanta q_res *
  page264_i44
#CELL
  pure_quanta q_res *
  page264_i45
#CELL
  pure_quanta q_res *
  page264_i46
#CELL
  pure_quanta q_cap *
  page264_i47
#CELL
  pure_quanta q_res *
  page264_i48
#ISCELL
  logical_power universal_gnd *
  page264_i49
#CELL
  pure_quanta q_res *
  page264_i5
#CELL
  pure_quanta q_cap *
  page264_i50
#CELL
  pure_quanta q_cap *
  page264_i51
#ISCELL
  logical_power universal_gnd *
  page264_i52
#CELL
  pure_quanta isl69260irazt *
  page264_i53
#ISCELL
  logical_power universal_gnd *
  page264_i54
#ISCELL
  logical_power universal_gnd *
  page264_i55
#CELL
  pure_quanta q_cap *
  page264_i56
#CELL
  pure_quanta q_res *
  page264_i57
#ISCELL
  logical_power universal_gnd *
  page264_i58
#CELL
  pure_quanta q_res *
  page264_i59
#CELL
  pure_quanta q_res *
  page264_i60
#CELL
  pure_quanta q_res *
  page264_i61
#CELL
  pure_quanta q_res *
  page264_i62
#CELL
  pure_quanta q_res *
  page264_i63
#ISCELL
  logical_power universal_gnd *
  page264_i64
#ISCELL
  logical_power universal_gnd *
  page264_i65
#CELL
  pure_quanta q_res *
  page264_i66
#CELL
  pure_quanta q_res *
  page264_i67
#CELL
  pure_quanta q_res *
  page264_i68
#CELL
  pure_quanta q_res *
  page264_i69
#CELL
  pure_quanta q_res *
  page264_i7
#CELL
  pure_quanta q_cap *
  page264_i70
#CELL
  pure_quanta q_cap *
  page264_i71
#CELL
  pure_quanta q_cap *
  page264_i72
#CELL
  pure_quanta q_cap *
  page264_i73
#CELL
  pure_quanta q_res *
  page264_i74
#ISCELL
  standard offpage *
  page264_i75
#ISCELL
  standard offpage *
  page264_i76
#ISCELL
  logical_power universal_gnd *
  page264_i77
#ISCELL
  logical_power universal_gnd *
  page264_i78
#ISCELL
  standard offpage *
  page264_i79
#ISCELL
  logical_power universal_gnd *
  page264_i8
#CELL
  pure_quanta q_res *
  page264_i80
#ISCELL
  logical_power vcc15 *
  page264_i81
#ISCELL
  standard offpage *
  page264_i82
#ISCELL
  logical_power universal_gnd *
  page264_i83
#ISCELL
  logical_power universal_gnd *
  page264_i84
#CELL
  pure_quanta q_res *
  page264_i85
#ISCELL
  logical_power vcc15 *
  page264_i86
#ISCELL
  logical_power universal_gnd *
  page264_i87
#ISCELL
  standard offpage *
  page264_i88
#ISCELL
  standard offpage *
  page264_i89
#CELL
  pure_quanta q_cap *
  page264_i9
#ISCELL
  logical_power universal_gnd *
  page264_i90
#ISCELL
  logical_power universal_gnd *
  page264_i91
#ISCELL
  logical_power universal_gnd *
  page264_i92
#ISCELL
  logical_power universal_gnd *
  page264_i93
#ISCELL
  logical_power universal_gnd *
  page264_i94
#CELL
  pure_quanta q_res *
  page264_i95
#CELL
  pure_quanta q_cap *
  page264_i96
